# T6G (Grand Teton) — schematic netlist excerpt (pin names and nets, part order shuffled) for the footprints in the layout excerpt that follows; sources: Cadence DE-HDL packaged netlist, KiCad conversion of 04192023_DAF0TMB3IC0_F0TG_MB_C_brd_V02_OCP.brd

PU17  ISL99390FRZTR5935  ISL99390FRZ-TR5935 IC  pkg QFN21_6X5XB  page 205
  VOS  = PVDDIO_P0_VOS1
  AGND  = GND
  VCC  = PVDDIO_P0_VCC1
  PVCC  = PVDDCR_CPU1_P0_PVCC
  PGND1  = GND
  GL1  = NC_PVDDIO_P0_GL1_1
  PGND2  = GND
  SW  = SW_PVDDIO_P0_SW1
  VIN1  = SW_P12V_AUX_PVDDIO_P0_FLT
  VIN2  = SW_P12V_AUX_PVDDIO_P0_FLT
  DNC  = NC_PVDDIO_P0_DNC1
  PHASE  = SW_PVDDIO_P0_BOOTR1
  BOOT  = SW_PVDDIO_P0_BOOT1
  PWM  = PVDDIO_P0_PWM1
  EN  = PVDDIO_P0_VCC1
  TOUT_FLT  = PVDDIO_P0_TEMP1
  LSET  = PVDDIO_P0_LSET1
  IOUT  = PVDDIO_P0_IMON1
  REFIN  = PVDDCR_CPU1_P0_VCCS
  PGND3  = GND
  GL2  = NC_PVDDIO_P0_GL2_1

(kicad_pcb
	(version 20260206)
	(generator "pcbnew")
	(generator_version "10.0")
	(general
		(thickness 1.6)
		(legacy_teardrops no)
	)
	(paper "A4")
	(title_block
		(title "04192023_DAF0TMB3IC0_F0TG_MB_C_brd_V02_OCP.brd")
		(comment 1 "Grand Teton / footprints 4009-4009 of 8354")
	)
	(layers
		(0 "F.Cu" signal "TOP")
		(4 "In1.Cu" signal "GND")
		(6 "In2.Cu" signal "IN1")
		(8 "In3.Cu" signal "GND1")
		(10 "In4.Cu" signal "IN2")
		(12 "In5.Cu" signal "GND2")
		(14 "In6.Cu" signal "IN3")
		(16 "In7.Cu" signal "GND3")
		(18 "In8.Cu" signal "VCC")
		(20 "In9.Cu" signal "VCC1")
		(22 "In10.Cu" signal "GND4")
		(24 "In11.Cu" signal "IN4")
		(26 "In12.Cu" signal "GND5")
		(28 "In13.Cu" signal "IN5")
		(30 "In14.Cu" signal "GND6")
		(32 "In15.Cu" signal "IN6")
		(34 "In16.Cu" signal "GND7")
		(2 "B.Cu" signal "BOTTOM")
		(9 "F.Adhes" user "F.Adhesive")
		(11 "B.Adhes" user "B.Adhesive")
		(13 "F.Paste" user "Package Geometry/Pastemask Top")
		(15 "B.Paste" user "Package Geometry/Pastemask Bottom")
		(5 "F.SilkS" user "Ref Des/Silkscreen Top")
		(7 "B.SilkS" user "Ref Des/Silkscreen Bottom")
		(1 "F.Mask" user "Board Geometry/Soldermask Top")
		(3 "B.Mask" user "Board Geometry/Soldermask Bottom")
		(17 "Dwgs.User" user "User.Drawings")
		(19 "Cmts.User" user "User.Comments")
		(21 "Eco1.User" user "User.Eco1")
		(23 "Eco2.User" user "User.Eco2")
		(25 "Edge.Cuts" user "Board Geometry/Outline")
		(27 "Margin" user)
		(31 "F.CrtYd" user "Package Geometry/Place Bound Top")
		(29 "B.CrtYd" user "Package Geometry/Place Bound Bottom")
		(35 "F.Fab" user "Ref Des/Assembly Top")
		(33 "B.Fab" user "Ref Des/Assembly Bottom")
	)
	(footprint ""
		(layer "F.Cu")
		(at 300.364906 -346.71635)
		(property "Reference" "PU17"
			(at -3.057906 -7.58698 0)
			(unlocked yes)
			(layer "F.SilkS")
			(effects
				(font
					(size 0.7874 0.5842)
					(thickness 0.1524)
				)
				(justify left)
			)
		)
		(property "Value" ""
			(at 0 0 0)
			(layer "F.Fab")
			(effects
				(font
					(size 1.27 1.27)
				)
			)
		)
		(duplicate_pad_numbers_are_jumpers no)
		(fp_line
			(start -2.500122 -2.999994)
			(end -2.24409 -2.999994)
			(stroke
				(width 0.1524)
				(type default)
			)
			(layer "F.SilkS")
		)
		(fp_line
			(start -2.500122 -2.529078)
			(end -2.500122 -2.999994)
			(stroke
				(width 0.1524)
				(type default)
			)
			(layer "F.SilkS")
		)
		(fp_line
			(start -2.500122 0.6604)
			(end -2.500122 0.229108)
			(stroke
				(width 0.1524)
				(type default)
			)
			(layer "F.SilkS")
		)
		(fp_line
			(start -2.500122 2.999994)
			(end -2.500122 2.339594)
			(stroke
				(width 0.1524)
				(type default)
			)
			(layer "F.SilkS")
		)
		(fp_line
			(start -2.2987 2.999994)
			(end -2.500122 2.999994)
			(stroke
				(width 0.1524)
				(type default)
			)
			(layer "F.SilkS")
		)
		(fp_line
			(start 2.31394 -2.999994)
			(end 2.500122 -2.999994)
			(stroke
				(width 0.1524)
				(type default)
			)
			(layer "F.SilkS")
		)
		(fp_line
			(start 2.500122 -2.999994)
			(end 2.500122 -2.44348)
			(stroke
				(width 0.1524)
				(type default)
			)
			(layer "F.SilkS")
		)
		(fp_line
			(start 2.500122 2.339594)
			(end 2.500122 2.999994)
			(stroke
				(width 0.1524)
				(type default)
			)
			(layer "F.SilkS")
		)
		(fp_line
			(start 2.500122 2.999994)
			(end 2.2987 2.999994)
			(stroke
				(width 0.1524)
				(type default)
			)
			(layer "F.SilkS")
		)
		(fp_poly
			(pts
				(xy -3.438144 -2.695956) (xy -2.972562 -3.161538) (xy -2.740152 -2.463546)
			)
			(stroke
				(width 0)
				(type default)
			)
			(fill yes)
			(layer "F.SilkS")
		)
		(fp_line
			(start -2.500122 -2.999994)
			(end 2.500122 -2.999994)
			(stroke
				(width 0.1)
				(type default)
			)
			(layer "F.Fab")
		)
		(fp_line
			(start -2.500122 2.999994)
			(end -2.500122 -2.999994)
			(stroke
				(width 0.1)
				(type default)
			)
			(layer "F.Fab")
		)
		(fp_line
			(start 2.500122 -2.999994)
			(end 2.500122 2.999994)
			(stroke
				(width 0.1)
				(type default)
			)
			(layer "F.Fab")
		)
		(fp_line
			(start 2.500122 2.999994)
			(end -2.500122 2.999994)
			(stroke
				(width 0.1)
				(type default)
			)
			(layer "F.Fab")
		)
		(fp_poly
			(pts
				(xy -4.218432 -2.783078) (xy -4.218432 -1.767078) (xy -3.202432 -2.275078)
			)
			(stroke
				(width 0)
				(type default)
			)
			(fill yes)
			(layer "F.Fab")
		)
		(pad "1" smd rect
			(at -2.400046 -2.275078 90)
			(size 0.2286 0.6096)
			(layers "F.Cu" "F.Mask" "F.Paste")
			(net "PVDDIO_P0_VOS1")
		)
		(pad "2" smd rect
			(at -2.400046 -1.82499 90)
			(size 0.2286 0.6096)
			(layers "F.Cu" "F.Mask" "F.Paste")
			(net "GND")
		)
		(pad "3" smd rect
			(at -2.400046 -1.374902 90)
			(size 0.2286 0.6096)
			(layers "F.Cu" "F.Mask" "F.Paste")
			(net "PVDDIO_P0_VCC1")
		)
		(pad "4" smd rect
			(at -2.400046 -0.925068 90)
			(size 0.2286 0.6096)
			(layers "F.Cu" "F.Mask" "F.Paste")
			(net "PVDDCR_CPU1_P0_PVCC")
		)
		(pad "5" smd rect
			(at -2.400046 -0.47498 90)
			(size 0.2286 0.6096)
			(layers "F.Cu" "F.Mask" "F.Paste")
			(net "GND")
		)
		(pad "6" smd rect
			(at -2.400046 -0.024892 90)
			(size 0.2286 0.6096)
			(layers "F.Cu" "F.Mask" "F.Paste")
			(net "NC_PVDDIO_P0_GL1_1")
		)
		(pad "7_9-20_24" smd circle
			(at 0 1.150112 90)
			(size 0 0)
			(layers "F.Cu" "F.Mask" "F.Paste")
			(net "GND")
		)
		(pad "10_19" smd rect
			(at 0 2.899918 90)
			(size 0.6096 4.318)
			(layers "F.Cu" "F.Mask" "F.Paste")
			(net "SW_PVDDIO_P0_SW1")
		)
		(pad "25_29" smd rect
			(at 1.549908 -1.279906 270)
			(size 2.0574 2.3114)
			(layers "F.Cu" "F.Mask" "F.Paste")
			(net "SW_P12V_AUX_PVDDIO_P0_FLT")
		)
		(pad "30" smd rect
			(at 2.05994 -2.899918)
			(size 0.2286 0.6096)
			(layers "F.Cu" "F.Mask" "F.Paste")
			(net "SW_P12V_AUX_PVDDIO_P0_FLT")
		)
		(pad "31" smd rect
			(at 1.610106 -2.899918)
			(size 0.2286 0.6096)
			(layers "F.Cu" "F.Mask" "F.Paste")
			(net "NC_PVDDIO_P0_DNC1")
		)
		(pad "32" smd rect
			(at 1.160018 -2.899918)
			(size 0.2286 0.6096)
			(layers "F.Cu" "F.Mask" "F.Paste")
			(net "SW_PVDDIO_P0_BOOTR1")
		)
		(pad "33" smd rect
			(at 0.70993 -2.899918)
			(size 0.2286 0.6096)
			(layers "F.Cu" "F.Mask" "F.Paste")
			(net "SW_PVDDIO_P0_BOOT1")
		)
		(pad "34" smd rect
			(at 0.260096 -2.899918)
			(size 0.2286 0.6096)
			(layers "F.Cu" "F.Mask" "F.Paste")
			(net "PVDDIO_P0_PWM1")
		)
		(pad "35" smd rect
			(at -0.189992 -2.899918)
			(size 0.2286 0.6096)
			(layers "F.Cu" "F.Mask" "F.Paste")
			(net "PVDDIO_P0_VCC1")
		)
		(pad "36" smd rect
			(at -0.64008 -2.899918)
			(size 0.2286 0.6096)
			(layers "F.Cu" "F.Mask" "F.Paste")
			(net "PVDDIO_P0_TEMP1")
		)
		(pad "37" smd rect
			(at -1.089914 -2.899918)
			(size 0.2286 0.6096)
			(layers "F.Cu" "F.Mask" "F.Paste")
			(net "PVDDIO_P0_LSET1")
		)
		(pad "38" smd rect
			(at -1.540002 -2.899918)
			(size 0.2286 0.6096)
			(layers "F.Cu" "F.Mask" "F.Paste")
			(net "PVDDIO_P0_IMON1")
		)
		(pad "39" smd rect
			(at -1.99009 -2.899918)
			(size 0.2286 0.6096)
			(layers "F.Cu" "F.Mask" "F.Paste")
			(net "PVDDCR_CPU1_P0_VCCS")
		)
		(pad "40" smd rect
			(at -0.87503 -1.27508)
			(size 1.7526 1.9558)
			(layers "F.Cu" "F.Mask" "F.Paste")
			(net "GND")
		)
		(pad "41" smd rect
			(at -1.525016 0.249936 270)
			(size 0.3048 0.4572)
			(layers "F.Cu" "F.Mask" "F.Paste")
			(net "NC_PVDDIO_P0_GL2_1")
		)
		(zone
			(layer "F.Cu")
			(hatch none 0.5)
			(connect_pads
				(clearance 0)
			)
			(min_thickness 0.25)
			(keepout
				(tracks not_allowed)
				(vias allowed)
				(pads allowed)
				(copperpour not_allowed)
				(footprints allowed)
			)
			(placement
				(enabled no)
				(sheetname "")
			)
			(fill
				(thermal_gap 0.5)
				(thermal_bridge_width 0.5)
				(island_removal_mode 0)
			)
			(polygon
				(pts
					(xy 297.864784 -344.138758) (xy 297.864784 -344.465656) (xy 302.865028 -344.465656) (xy 302.865028 -344.130884)
					(xy 302.574706 -344.130884) (xy 302.574706 -344.172032) (xy 298.155106 -344.172032) (xy 298.155106 -344.138758)
				)
			)
		)
		(zone
			(layer "F.Cu")
			(hatch none 0.5)
			(connect_pads
				(clearance 0)
			)
			(min_thickness 0.25)
			(keepout
				(tracks not_allowed)
				(vias allowed)
				(pads allowed)
				(copperpour not_allowed)
				(footprints allowed)
			)
			(placement
				(enabled no)
				(sheetname "")
			)
			(fill
				(thermal_gap 0.5)
				(thermal_bridge_width 0.5)
				(island_removal_mode 0)
			)
			(polygon
				(pts
					(xy 300.416976 -346.96273) (xy 300.416976 -349.02013) (xy 298.562776 -349.02013) (xy 298.562776 -348.779084)
					(xy 298.32046 -348.779084) (xy 298.32046 -349.260668) (xy 302.123094 -349.260668) (xy 302.123094 -349.075756)
					(xy 300.708314 -349.075756) (xy 300.708314 -346.916756) (xy 302.865028 -346.916756) (xy 302.865028 -346.667074)
					(xy 300.661578 -346.667074) (xy 300.416976 -346.911676)
				)
			)
		)
	)
)
